# T6G (Grand Teton) — schematic netlist excerpt (pin names and nets, part order shuffled) for the footprints in the layout excerpt that follows; sources: Cadence DE-HDL packaged netlist, KiCad conversion of 04192023_DAF0TMB3IC0_F0TG_MB_C_brd_V02_OCP.brd

PC2234  Q_CAP  1UF 25V 10% X6S  pkg C0402  page 152 : A = GND ; B = P12V_SCM_REG
C8017  Q_CAP  100NF 50V 10% EMPTY  pkg C0402  page 268 : A = UV_ADR_P2V5_COMP ; B = GND

(kicad_pcb
	(version 20260206)
	(generator "pcbnew")
	(generator_version "10.0")
	(general
		(thickness 1.6)
		(legacy_teardrops no)
	)
	(paper "A4")
	(title_block
		(title "04192023_DAF0TMB3IC0_F0TG_MB_C_brd_V02_OCP.brd")
		(comment 1 "Grand Teton / footprints 3959-3960 of 8354")
	)
	(layers
		(0 "F.Cu" signal "TOP")
		(4 "In1.Cu" signal "GND")
		(6 "In2.Cu" signal "IN1")
		(8 "In3.Cu" signal "GND1")
		(10 "In4.Cu" signal "IN2")
		(12 "In5.Cu" signal "GND2")
		(14 "In6.Cu" signal "IN3")
		(16 "In7.Cu" signal "GND3")
		(18 "In8.Cu" signal "VCC")
		(20 "In9.Cu" signal "VCC1")
		(22 "In10.Cu" signal "GND4")
		(24 "In11.Cu" signal "IN4")
		(26 "In12.Cu" signal "GND5")
		(28 "In13.Cu" signal "IN5")
		(30 "In14.Cu" signal "GND6")
		(32 "In15.Cu" signal "IN6")
		(34 "In16.Cu" signal "GND7")
		(2 "B.Cu" signal "BOTTOM")
		(9 "F.Adhes" user "F.Adhesive")
		(11 "B.Adhes" user "B.Adhesive")
		(13 "F.Paste" user "Package Geometry/Pastemask Top")
		(15 "B.Paste" user "Package Geometry/Pastemask Bottom")
		(5 "F.SilkS" user "Ref Des/Silkscreen Top")
		(7 "B.SilkS" user "Ref Des/Silkscreen Bottom")
		(1 "F.Mask" user "Board Geometry/Soldermask Top")
		(3 "B.Mask" user "Board Geometry/Soldermask Bottom")
		(17 "Dwgs.User" user "User.Drawings")
		(19 "Cmts.User" user "User.Comments")
		(21 "Eco1.User" user "User.Eco1")
		(23 "Eco2.User" user "User.Eco2")
		(25 "Edge.Cuts" user "Board Geometry/Outline")
		(27 "Margin" user)
		(31 "F.CrtYd" user "Package Geometry/Place Bound Top")
		(29 "B.CrtYd" user "Package Geometry/Place Bound Bottom")
		(35 "F.Fab" user "Ref Des/Assembly Top")
		(33 "B.Fab" user "Ref Des/Assembly Bottom")
	)
	(footprint ""
		(layer "F.Cu")
		(at 127.381 -108.712 90)
		(property "Reference" "C8017"
			(at 0 0 90)
			(layer "F.SilkS")
			(hide yes)
			(effects
				(font
					(size 1.27 1.27)
				)
			)
		)
		(property "Value" ""
			(at 0 0 90)
			(layer "F.Fab")
			(effects
				(font
					(size 1.27 1.27)
				)
			)
		)
		(duplicate_pad_numbers_are_jumpers no)
		(fp_line
			(start 0.7874 -0.4064)
			(end 0.7874 0.4064)
			(stroke
				(width 0.1524)
				(type default)
			)
			(layer "F.SilkS")
		)
		(fp_line
			(start -0.7874 -0.4064)
			(end 0.7874 -0.4064)
			(stroke
				(width 0.1524)
				(type default)
			)
			(layer "F.SilkS")
		)
		(fp_line
			(start 0.7874 0.4064)
			(end -0.7874 0.4064)
			(stroke
				(width 0.1524)
				(type default)
			)
			(layer "F.SilkS")
		)
		(fp_line
			(start -0.7874 0.4064)
			(end -0.7874 -0.4064)
			(stroke
				(width 0.1524)
				(type default)
			)
			(layer "F.SilkS")
		)
		(fp_line
			(start -0.12065 -0.305054)
			(end -0.12065 -0.2794)
			(stroke
				(width 0.1)
				(type default)
			)
			(layer "F.Fab")
		)
		(fp_line
			(start -0.67945 -0.305054)
			(end -0.12065 -0.305054)
			(stroke
				(width 0.1)
				(type default)
			)
			(layer "F.Fab")
		)
		(fp_line
			(start 0.67945 -0.3048)
			(end 0.67945 0.3048)
			(stroke
				(width 0.1)
				(type default)
			)
			(layer "F.Fab")
		)
		(fp_line
			(start 0.12065 -0.3048)
			(end 0.67945 -0.3048)
			(stroke
				(width 0.1)
				(type default)
			)
			(layer "F.Fab")
		)
		(fp_line
			(start 0.12065 -0.2794)
			(end 0.12065 -0.3048)
			(stroke
				(width 0.1)
				(type default)
			)
			(layer "F.Fab")
		)
		(fp_line
			(start -0.12065 -0.2794)
			(end 0.12065 -0.2794)
			(stroke
				(width 0.1)
				(type default)
			)
			(layer "F.Fab")
		)
		(fp_line
			(start 0.120396 0.2794)
			(end -0.12065 0.2794)
			(stroke
				(width 0.1)
				(type default)
			)
			(layer "F.Fab")
		)
		(fp_line
			(start -0.12065 0.2794)
			(end -0.12065 0.3048)
			(stroke
				(width 0.1)
				(type default)
			)
			(layer "F.Fab")
		)
		(fp_line
			(start 0.67945 0.3048)
			(end 0.120396 0.3048)
			(stroke
				(width 0.1)
				(type default)
			)
			(layer "F.Fab")
		)
		(fp_line
			(start 0.120396 0.3048)
			(end 0.120396 0.2794)
			(stroke
				(width 0.1)
				(type default)
			)
			(layer "F.Fab")
		)
		(fp_line
			(start -0.12065 0.3048)
			(end -0.67945 0.3048)
			(stroke
				(width 0.1)
				(type default)
			)
			(layer "F.Fab")
		)
		(fp_line
			(start -0.67945 0.3048)
			(end -0.67945 -0.305054)
			(stroke
				(width 0.1)
				(type default)
			)
			(layer "F.Fab")
		)
		(pad "1" smd circle
			(at -0.40005 0 90)
			(size 0 0)
			(layers "F.Cu" "F.Mask" "F.Paste")
			(net "UV_ADR_P2V5_COMP")
		)
		(pad "2" smd circle
			(at 0.40005 0 90)
			(size 0 0)
			(layers "F.Cu" "F.Mask" "F.Paste")
			(net "GND")
		)
	)
	(footprint ""
		(layer "F.Cu")
		(at 185.806842 -24.170132)
		(property "Reference" "PC2234"
			(at 0 0 0)
			(layer "F.SilkS")
			(hide yes)
			(effects
				(font
					(size 1.27 1.27)
				)
			)
		)
		(property "Value" ""
			(at 0 0 0)
			(layer "F.Fab")
			(effects
				(font
					(size 1.27 1.27)
				)
			)
		)
		(duplicate_pad_numbers_are_jumpers no)
		(fp_line
			(start -0.7874 -0.4064)
			(end 0.7874 -0.4064)
			(stroke
				(width 0.1524)
				(type default)
			)
			(layer "F.SilkS")
		)
		(fp_line
			(start -0.7874 0.4064)
			(end -0.7874 -0.4064)
			(stroke
				(width 0.1524)
				(type default)
			)
			(layer "F.SilkS")
		)
		(fp_line
			(start 0.7874 -0.4064)
			(end 0.7874 0.4064)
			(stroke
				(width 0.1524)
				(type default)
			)
			(layer "F.SilkS")
		)
		(fp_line
			(start 0.7874 0.4064)
			(end -0.7874 0.4064)
			(stroke
				(width 0.1524)
				(type default)
			)
			(layer "F.SilkS")
		)
		(fp_line
			(start -0.67945 -0.305054)
			(end -0.12065 -0.305054)
			(stroke
				(width 0.1)
				(type default)
			)
			(layer "F.Fab")
		)
		(fp_line
			(start -0.67945 0.3048)
			(end -0.67945 -0.305054)
			(stroke
				(width 0.1)
				(type default)
			)
			(layer "F.Fab")
		)
		(fp_line
			(start -0.12065 -0.305054)
			(end -0.12065 -0.2794)
			(stroke
				(width 0.1)
				(type default)
			)
			(layer "F.Fab")
		)
		(fp_line
			(start -0.12065 -0.2794)
			(end 0.12065 -0.2794)
			(stroke
				(width 0.1)
				(type default)
			)
			(layer "F.Fab")
		)
		(fp_line
			(start -0.12065 0.2794)
			(end -0.12065 0.3048)
			(stroke
				(width 0.1)
				(type default)
			)
			(layer "F.Fab")
		)
		(fp_line
			(start -0.12065 0.3048)
			(end -0.67945 0.3048)
			(stroke
				(width 0.1)
				(type default)
			)
			(layer "F.Fab")
		)
		(fp_line
			(start 0.120396 0.2794)
			(end -0.12065 0.2794)
			(stroke
				(width 0.1)
				(type default)
			)
			(layer "F.Fab")
		)
		(fp_line
			(start 0.120396 0.3048)
			(end 0.120396 0.2794)
			(stroke
				(width 0.1)
				(type default)
			)
			(layer "F.Fab")
		)
		(fp_line
			(start 0.12065 -0.3048)
			(end 0.67945 -0.3048)
			(stroke
				(width 0.1)
				(type default)
			)
			(layer "F.Fab")
		)
		(fp_line
			(start 0.12065 -0.2794)
			(end 0.12065 -0.3048)
			(stroke
				(width 0.1)
				(type default)
			)
			(layer "F.Fab")
		)
		(fp_line
			(start 0.67945 -0.3048)
			(end 0.67945 0.3048)
			(stroke
				(width 0.1)
				(type default)
			)
			(layer "F.Fab")
		)
		(fp_line
			(start 0.67945 0.3048)
			(end 0.120396 0.3048)
			(stroke
				(width 0.1)
				(type default)
			)
			(layer "F.Fab")
		)
		(pad "1" smd circle
			(at -0.40005 0)
			(size 0 0)
			(layers "F.Cu" "F.Mask" "F.Paste")
			(net "GND")
		)
		(pad "2" smd circle
			(at 0.40005 0)
			(size 0 0)
			(layers "F.Cu" "F.Mask" "F.Paste")
			(net "P12V_SCM_REG")
		)
	)
)
